(kicad_pcb
	(version 20260206)
	(generator "pcbnew")
	(generator_version "10.0")
	(general
		(thickness 1.6)
		(legacy_teardrops no)
	)
	(paper "A4")
	(title_block
		(title "baseboard — 13948-1b.1110WZS1818.brd")
		(comment 1 "Honey Badger (Wiwynn) / footprints 1768-1772 of 2523")
	)
	(layers
		(0 "F.Cu" signal "TOP")
		(4 "In1.Cu" signal "L2GND")
		(6 "In2.Cu" signal "L3")
		(8 "In3.Cu" signal "L4VCC")
		(10 "In4.Cu" signal "L5VCC")
		(12 "In5.Cu" signal "L6")
		(14 "In6.Cu" signal "L7GND")
		(2 "B.Cu" signal "BOTTOM")
		(9 "F.Adhes" user "F.Adhesive")
		(11 "B.Adhes" user "B.Adhesive")
		(13 "F.Paste" user "Package Geometry/Pastemask Top")
		(15 "B.Paste" user "Package Geometry/Pastemask Bottom")
		(5 "F.SilkS" user "Ref Des/Silkscreen Top")
		(7 "B.SilkS" user "Ref Des/Silkscreen Bottom")
		(1 "F.Mask" user "Board Geometry/Soldermask Top")
		(3 "B.Mask" user "Board Geometry/Soldermask Bottom")
		(17 "Dwgs.User" user "User.Drawings")
		(19 "Cmts.User" user "User.Comments")
		(21 "Eco1.User" user "User.Eco1")
		(23 "Eco2.User" user "User.Eco2")
		(25 "Edge.Cuts" user "Board Geometry/Outline")
		(27 "Margin" user)
		(31 "F.CrtYd" user "Package Geometry/Place Bound Top")
		(29 "B.CrtYd" user "Package Geometry/Place Bound Bottom")
		(35 "F.Fab" user "Ref Des/Assembly Top")
		(33 "B.Fab" user "Ref Des/Assembly Bottom")
	)
	(footprint ""
		(layer "F.Cu")
		(at 29.884116 -77.585062 180)
		(property "Reference" "Q5"
			(at 0 0 180)
			(layer "F.SilkS")
			(hide yes)
			(effects
				(font
					(size 1.27 1.27)
				)
			)
		)
		(property "Value" "PMBS3904-1-GP"
			(at 0 -9.0932 180)
			(unlocked yes)
			(layer "F.Fab")
			(hide yes)
			(effects
				(font
					(size 1.016 1.016)
					(thickness 0.1524)
				)
			)
		)
		(property "Device Type" "SOT-23-10H44"
			(at 0 -10.6172 180)
			(unlocked yes)
			(layer "F.Fab")
			(hide yes)
			(effects
				(font
					(size 1.016 1.016)
					(thickness 0.1524)
				)
			)
		)
		(duplicate_pad_numbers_are_jumpers no)
		(fp_line
			(start 1.651 1.778)
			(end 1.651 -1.778)
			(stroke
				(width 0.1524)
				(type default)
			)
			(layer "F.SilkS")
		)
		(fp_line
			(start 1.651 -1.778)
			(end -1.651 -1.778)
			(stroke
				(width 0.1524)
				(type default)
			)
			(layer "F.SilkS")
		)
		(fp_line
			(start -0.635 1.8796)
			(end -1.7526 1.8796)
			(stroke
				(width 0.3302)
				(type default)
			)
			(layer "F.SilkS")
		)
		(fp_line
			(start -0.71628 2.15265)
			(end -1.26492 2.15265)
			(stroke
				(width 0.0127)
				(type default)
			)
			(layer "F.SilkS")
		)
		(fp_line
			(start -0.719074 2.145538)
			(end -1.265936 2.14122)
			(stroke
				(width 0.0127)
				(type default)
			)
			(layer "F.SilkS")
		)
		(fp_line
			(start -0.9906 1.86309)
			(end -0.701294 2.15265)
			(stroke
				(width 0.0127)
				(type default)
			)
			(layer "F.SilkS")
		)
		(fp_line
			(start -0.994156 1.8669)
			(end -0.987044 1.8669)
			(stroke
				(width 0.0127)
				(type default)
			)
			(layer "F.SilkS")
		)
		(fp_line
			(start -1.003808 1.876552)
			(end -0.977646 1.876552)
			(stroke
				(width 0.0127)
				(type default)
			)
			(layer "F.SilkS")
		)
		(fp_line
			(start -1.013206 1.88595)
			(end -0.967994 1.88595)
			(stroke
				(width 0.0127)
				(type default)
			)
			(layer "F.SilkS")
		)
		(fp_line
			(start -1.022858 1.895602)
			(end -0.958596 1.895602)
			(stroke
				(width 0.0127)
				(type default)
			)
			(layer "F.SilkS")
		)
		(fp_line
			(start -1.032256 1.905)
			(end -0.948944 1.905)
			(stroke
				(width 0.0127)
				(type default)
			)
			(layer "F.SilkS")
		)
		(fp_line
			(start -1.041908 1.914652)
			(end -0.939546 1.914652)
			(stroke
				(width 0.0127)
				(type default)
			)
			(layer "F.SilkS")
		)
		(fp_line
			(start -1.051306 1.92405)
			(end -0.929894 1.92405)
			(stroke
				(width 0.0127)
				(type default)
			)
			(layer "F.SilkS")
		)
		(fp_line
			(start -1.060958 1.933702)
			(end -0.920496 1.933702)
			(stroke
				(width 0.0127)
				(type default)
			)
			(layer "F.SilkS")
		)
		(fp_line
			(start -1.070356 1.9431)
			(end -0.910844 1.9431)
			(stroke
				(width 0.0127)
				(type default)
			)
			(layer "F.SilkS")
		)
		(fp_line
			(start -1.080008 1.952752)
			(end -0.901446 1.952752)
			(stroke
				(width 0.0127)
				(type default)
			)
			(layer "F.SilkS")
		)
		(fp_line
			(start -1.089406 1.96215)
			(end -0.891794 1.96215)
			(stroke
				(width 0.0127)
				(type default)
			)
			(layer "F.SilkS")
		)
		(fp_line
			(start -1.099058 1.971802)
			(end -0.882396 1.971802)
			(stroke
				(width 0.0127)
				(type default)
			)
			(layer "F.SilkS")
		)
		(fp_line
			(start -1.108456 1.9812)
			(end -0.872744 1.9812)
			(stroke
				(width 0.0127)
				(type default)
			)
			(layer "F.SilkS")
		)
		(fp_line
			(start -1.118108 1.990852)
			(end -0.863346 1.990852)
			(stroke
				(width 0.0127)
				(type default)
			)
			(layer "F.SilkS")
		)
		(fp_line
			(start -1.127506 2.00025)
			(end -0.853694 2.00025)
			(stroke
				(width 0.0127)
				(type default)
			)
			(layer "F.SilkS")
		)
		(fp_line
			(start -1.137158 2.009902)
			(end -0.844296 2.009902)
			(stroke
				(width 0.0127)
				(type default)
			)
			(layer "F.SilkS")
		)
		(fp_line
			(start -1.146556 2.0193)
			(end -0.834644 2.0193)
			(stroke
				(width 0.0127)
				(type default)
			)
			(layer "F.SilkS")
		)
		(fp_line
			(start -1.156208 2.028952)
			(end -0.825246 2.028952)
			(stroke
				(width 0.0127)
				(type default)
			)
			(layer "F.SilkS")
		)
		(fp_line
			(start -1.165606 2.03835)
			(end -0.815594 2.03835)
			(stroke
				(width 0.0127)
				(type default)
			)
			(layer "F.SilkS")
		)
		(fp_line
			(start -1.175258 2.048002)
			(end -0.806196 2.048002)
			(stroke
				(width 0.0127)
				(type default)
			)
			(layer "F.SilkS")
		)
		(fp_line
			(start -1.184656 2.0574)
			(end -0.796544 2.0574)
			(stroke
				(width 0.0127)
				(type default)
			)
			(layer "F.SilkS")
		)
		(fp_line
			(start -1.194308 2.067052)
			(end -0.787146 2.067052)
			(stroke
				(width 0.0127)
				(type default)
			)
			(layer "F.SilkS")
		)
		(fp_line
			(start -1.203706 2.07645)
			(end -0.777494 2.07645)
			(stroke
				(width 0.0127)
				(type default)
			)
			(layer "F.SilkS")
		)
		(fp_line
			(start -1.213358 2.086102)
			(end -0.768096 2.086102)
			(stroke
				(width 0.0127)
				(type default)
			)
			(layer "F.SilkS")
		)
		(fp_line
			(start -1.222756 2.0955)
			(end -0.758444 2.0955)
			(stroke
				(width 0.0127)
				(type default)
			)
			(layer "F.SilkS")
		)
		(fp_line
			(start -1.232408 2.105152)
			(end -0.749046 2.105152)
			(stroke
				(width 0.0127)
				(type default)
			)
			(layer "F.SilkS")
		)
		(fp_line
			(start -1.241806 2.11455)
			(end -0.739394 2.11455)
			(stroke
				(width 0.0127)
				(type default)
			)
			(layer "F.SilkS")
		)
		(fp_line
			(start -1.251458 2.124202)
			(end -0.729996 2.124202)
			(stroke
				(width 0.0127)
				(type default)
			)
			(layer "F.SilkS")
		)
		(fp_line
			(start -1.260856 2.1336)
			(end -0.720344 2.1336)
			(stroke
				(width 0.0127)
				(type default)
			)
			(layer "F.SilkS")
		)
		(fp_line
			(start -1.279144 2.15265)
			(end -0.701294 2.15265)
			(stroke
				(width 0.0127)
				(type default)
			)
			(layer "F.SilkS")
		)
		(fp_line
			(start -1.279398 2.152142)
			(end -0.9906 1.86309)
			(stroke
				(width 0.0127)
				(type default)
			)
			(layer "F.SilkS")
		)
		(fp_line
			(start -1.651 1.778)
			(end 1.651 1.778)
			(stroke
				(width 0.1524)
				(type default)
			)
			(layer "F.SilkS")
		)
		(fp_line
			(start -1.651 -1.778)
			(end -1.651 1.778)
			(stroke
				(width 0.1524)
				(type default)
			)
			(layer "F.SilkS")
		)
		(fp_line
			(start -1.7526 1.8796)
			(end -1.7526 0.9906)
			(stroke
				(width 0.3302)
				(type default)
			)
			(layer "F.SilkS")
		)
		(fp_poly
			(pts
				(xy -1.285748 2.159) (xy -1.285748 1.8796) (xy -1.778 1.8796) (xy -1.778 -1.8796) (xy 1.778 -1.8796)
				(xy 1.778 1.8796) (xy -0.694944 1.8796) (xy -0.694944 2.159)
			)
			(stroke
				(width 0)
				(type default)
			)
			(fill no)
			(layer "F.CrtYd")
		)
		(fp_poly
			(pts
				(xy -1.285748 2.159) (xy -1.285748 1.8796) (xy -1.778 1.8796) (xy -1.778 -1.8796) (xy 1.778 -1.8796)
				(xy 1.778 1.8796) (xy -0.694944 1.8796) (xy -0.694944 2.159)
			)
			(stroke
				(width 0)
				(type default)
			)
			(fill no)
			(layer "F.Fab")
		)
		(pad "1" smd rect
			(at -0.98425 0.9525 180)
			(size 0.762 1.143)
			(layers "F.Cu" "F.Mask" "F.Paste")
			(net "INTA_LED_RED_B")
		)
		(pad "2" smd rect
			(at 0.98425 0.9525 180)
			(size 0.762 1.143)
			(layers "F.Cu" "F.Mask" "F.Paste")
			(net "GND")
		)
		(pad "3" smd rect
			(at 0 -0.9525 180)
			(size 0.762 1.143)
			(layers "F.Cu" "F.Mask" "F.Paste")
			(net "INTA_LED_RED_C")
		)
	)
	(footprint ""
		(layer "F.Cu")
		(at 202.565 -140.589 -90)
		(property "Reference" "SR759"
			(at 0 0 270)
			(layer "F.SilkS")
			(hide yes)
			(effects
				(font
					(size 1.27 1.27)
				)
			)
		)
		(property "Value" "4K7R2F-GP"
			(at 0.064008 -3.993896 270)
			(unlocked yes)
			(layer "F.Fab")
			(hide yes)
			(effects
				(font
					(size 1.016 1.016)
					(thickness 0.1524)
				)
			)
		)
		(property "Device Type" "R402H16"
			(at 0.064008 -5.517896 270)
			(unlocked yes)
			(layer "F.Fab")
			(hide yes)
			(effects
				(font
					(size 1.016 1.016)
					(thickness 0.1524)
				)
			)
		)
		(duplicate_pad_numbers_are_jumpers no)
		(fp_line
			(start -0.508 -0.9398)
			(end -0.508 0.9398)
			(stroke
				(width 0.1524)
				(type default)
			)
			(layer "F.SilkS")
		)
		(fp_line
			(start 0.508 -0.9398)
			(end -0.508 -0.9398)
			(stroke
				(width 0.1524)
				(type default)
			)
			(layer "F.SilkS")
		)
		(fp_rect
			(start -0.508 0.9398)
			(end 0.508 -0.9398)
			(stroke
				(width 0)
				(type default)
			)
			(fill no)
			(layer "F.CrtYd")
		)
		(fp_rect
			(start -0.508 0.9398)
			(end 0.508 -0.9398)
			(stroke
				(width 0)
				(type default)
			)
			(fill no)
			(layer "F.Fab")
		)
		(pad "1" smd custom
			(at 0 -0.4445 270)
			(size 0.1397 0.1397)
			(layers "F.Cu" "F.Mask" "F.Paste")
			(net "P1V8_E")
			(options
				(clearance outline)
				(anchor circle)
			)
			(primitives
				(gr_poly
					(pts
						(arc
							(start -0.1778 -0.2794)
							(mid -0.249642 -0.249642)
							(end -0.2794 -0.1778)
						)
						(arc
							(start -0.2794 0.1778)
							(mid -0.249642 0.249642)
							(end -0.1778 0.2794)
						)
						(arc
							(start 0.1778 0.2794)
							(mid 0.249642 0.249642)
							(end 0.2794 0.1778)
						)
						(arc
							(start 0.2794 -0.1778)
							(mid 0.249642 -0.249642)
							(end 0.1778 -0.2794)
						)
					)
					(width 0)
					(fill yes)
				)
			)
		)
		(pad "2" smd custom
			(at 0 0.4445 270)
			(size 0.1397 0.1397)
			(layers "F.Cu" "F.Mask" "F.Paste")
			(net "EXP_EEPROM_A1")
			(options
				(clearance outline)
				(anchor circle)
			)
			(primitives
				(gr_poly
					(pts
						(arc
							(start -0.1778 -0.2794)
							(mid -0.249642 -0.249642)
							(end -0.2794 -0.1778)
						)
						(arc
							(start -0.2794 0.1778)
							(mid -0.249642 0.249642)
							(end -0.1778 0.2794)
						)
						(arc
							(start 0.1778 0.2794)
							(mid 0.249642 0.249642)
							(end 0.2794 0.1778)
						)
						(arc
							(start 0.2794 -0.1778)
							(mid 0.249642 -0.249642)
							(end 0.1778 -0.2794)
						)
					)
					(width 0)
					(fill yes)
				)
			)
		)
	)
	(footprint ""
		(layer "F.Cu")
		(at 189.865 -22.479 90)
		(property "Reference" "R381"
			(at 0 0 90)
			(layer "F.SilkS")
			(hide yes)
			(effects
				(font
					(size 1.27 1.27)
				)
			)
		)
		(property "Value" "0R2J-2-GP"
			(at 0.064008 -3.993896 90)
			(unlocked yes)
			(layer "F.Fab")
			(hide yes)
			(effects
				(font
					(size 1.016 1.016)
					(thickness 0.1524)
				)
			)
		)
		(property "Device Type" "R402H16"
			(at 0.064008 -5.517896 90)
			(unlocked yes)
			(layer "F.Fab")
			(hide yes)
			(effects
				(font
					(size 1.016 1.016)
					(thickness 0.1524)
				)
			)
		)
		(duplicate_pad_numbers_are_jumpers no)
		(fp_line
			(start 0.508 -0.9398)
			(end -0.508 -0.9398)
			(stroke
				(width 0.1524)
				(type default)
			)
			(layer "F.SilkS")
		)
		(fp_line
			(start -0.508 -0.9398)
			(end -0.508 0.9398)
			(stroke
				(width 0.1524)
				(type default)
			)
			(layer "F.SilkS")
		)
		(fp_rect
			(start -0.508 0.9398)
			(end 0.508 -0.9398)
			(stroke
				(width 0)
				(type default)
			)
			(fill no)
			(layer "F.CrtYd")
		)
		(fp_rect
			(start -0.508 0.9398)
			(end 0.508 -0.9398)
			(stroke
				(width 0)
				(type default)
			)
			(fill no)
			(layer "F.Fab")
		)
		(pad "1" smd custom
			(at 0 -0.4445 90)
			(size 0.1397 0.1397)
			(layers "F.Cu" "F.Mask" "F.Paste")
			(net "RMII_BMC_MDC_R")
			(options
				(clearance outline)
				(anchor circle)
			)
			(primitives
				(gr_poly
					(pts
						(arc
							(start -0.1778 -0.2794)
							(mid -0.249642 -0.249642)
							(end -0.2794 -0.1778)
						)
						(arc
							(start -0.2794 0.1778)
							(mid -0.249642 0.249642)
							(end -0.1778 0.2794)
						)
						(arc
							(start 0.1778 0.2794)
							(mid 0.249642 0.249642)
							(end 0.2794 0.1778)
						)
						(arc
							(start 0.2794 -0.1778)
							(mid 0.249642 -0.249642)
							(end 0.1778 -0.2794)
						)
					)
					(width 0)
					(fill yes)
				)
			)
		)
		(pad "2" smd custom
			(at 0 0.4445 90)
			(size 0.1397 0.1397)
			(layers "F.Cu" "F.Mask" "F.Paste")
			(net "RMII_BMC_MDC")
			(options
				(clearance outline)
				(anchor circle)
			)
			(primitives
				(gr_poly
					(pts
						(arc
							(start -0.1778 -0.2794)
							(mid -0.249642 -0.249642)
							(end -0.2794 -0.1778)
						)
						(arc
							(start -0.2794 0.1778)
							(mid -0.249642 0.249642)
							(end -0.1778 0.2794)
						)
						(arc
							(start 0.1778 0.2794)
							(mid 0.249642 0.249642)
							(end 0.2794 0.1778)
						)
						(arc
							(start 0.2794 -0.1778)
							(mid 0.249642 -0.249642)
							(end 0.1778 -0.2794)
						)
					)
					(width 0)
					(fill yes)
				)
			)
		)
	)
	(footprint ""
		(layer "B.Cu")
		(at 98.787966 -44.196 -90)
		(property "Reference" "SC1063"
			(at 0 0 90)
			(layer "B.SilkS")
			(hide yes)
			(effects
				(font
					(size 1.27 1.27)
				)
				(justify mirror)
			)
		)
		(property "Value" "SCD1U16V2KX-3GP"
			(at -1.1811 -2.7051 270)
			(unlocked yes)
			(layer "B.Fab")
			(hide yes)
			(effects
				(font
					(size 1.016 1.016)
					(thickness 0.1524)
				)
				(justify mirror)
			)
		)
		(property "Device Type" "C402H22"
			(at -1.1811 -4.2291 270)
			(unlocked yes)
			(layer "B.Fab")
			(hide yes)
			(effects
				(font
					(size 1.016 1.016)
					(thickness 0.1524)
				)
				(justify mirror)
			)
		)
		(duplicate_pad_numbers_are_jumpers no)
		(fp_rect
			(start 0.4318 0.9525)
			(end -0.4318 -0.9525)
			(stroke
				(width 0)
				(type default)
			)
			(fill no)
			(layer "B.CrtYd")
		)
		(fp_rect
			(start 0.4318 0.9525)
			(end -0.4318 -0.9525)
			(stroke
				(width 0)
				(type default)
			)
			(fill no)
			(layer "B.Fab")
		)
		(pad "1" smd custom
			(at 0 -0.4445 90)
			(size 0.1524 0.1524)
			(layers "B.Cu" "B.Mask" "B.Paste")
			(net "P0V955_C")
			(options
				(clearance outline)
				(anchor circle)
			)
			(primitives
				(gr_poly
					(pts
						(arc
							(start 0.3048 0.2032)
							(mid 0.275042 0.275042)
							(end 0.2032 0.3048)
						)
						(arc
							(start -0.2032 0.3048)
							(mid -0.275042 0.275042)
							(end -0.3048 0.2032)
						)
						(arc
							(start -0.3048 -0.2032)
							(mid -0.275042 -0.275042)
							(end -0.2032 -0.3048)
						)
						(arc
							(start 0.2032 -0.3048)
							(mid 0.275042 -0.275042)
							(end 0.3048 -0.2032)
						)
					)
					(width 0)
					(fill yes)
				)
			)
		)
		(pad "2" smd custom
			(at 0 0.4445 90)
			(size 0.1524 0.1524)
			(layers "B.Cu" "B.Mask" "B.Paste")
			(net "GND")
			(options
				(clearance outline)
				(anchor circle)
			)
			(primitives
				(gr_poly
					(pts
						(arc
							(start 0.3048 0.2032)
							(mid 0.275042 0.275042)
							(end 0.2032 0.3048)
						)
						(arc
							(start -0.2032 0.3048)
							(mid -0.275042 0.275042)
							(end -0.3048 0.2032)
						)
						(arc
							(start -0.3048 -0.2032)
							(mid -0.275042 -0.275042)
							(end -0.2032 -0.3048)
						)
						(arc
							(start 0.2032 -0.3048)
							(mid 0.275042 -0.275042)
							(end 0.3048 -0.2032)
						)
					)
					(width 0)
					(fill yes)
				)
			)
		)
	)
	(footprint ""
		(layer "B.Cu")
		(at 76.073 -25.019 -90)
		(property "Reference" "SR931"
			(at 0 0 90)
			(layer "B.SilkS")
			(hide yes)
			(effects
				(font
					(size 1.27 1.27)
				)
				(justify mirror)
			)
		)
		(property "Value" "10KR2F-2-GP"
			(at -0.064008 -3.993896 270)
			(unlocked yes)
			(layer "B.Fab")
			(hide yes)
			(effects
				(font
					(size 1.016 1.016)
					(thickness 0.1524)
				)
				(justify mirror)
			)
		)
		(property "Device Type" "R402H16"
			(at -0.064008 -5.517896 270)
			(unlocked yes)
			(layer "B.Fab")
			(hide yes)
			(effects
				(font
					(size 1.016 1.016)
					(thickness 0.1524)
				)
				(justify mirror)
			)
		)
		(duplicate_pad_numbers_are_jumpers no)
		(fp_line
			(start -0.508 -0.9398)
			(end 0.508 -0.9398)
			(stroke
				(width 0.1524)
				(type default)
			)
			(layer "B.SilkS")
		)
		(fp_line
			(start 0.508 -0.9398)
			(end 0.508 0.9398)
			(stroke
				(width 0.1524)
				(type default)
			)
			(layer "B.SilkS")
		)
		(fp_rect
			(start 0.508 0.9398)
			(end -0.508 -0.9398)
			(stroke
				(width 0)
				(type default)
			)
			(fill no)
			(layer "B.CrtYd")
		)
		(fp_rect
			(start 0.508 0.9398)
			(end -0.508 -0.9398)
			(stroke
				(width 0)
				(type default)
			)
			(fill no)
			(layer "B.Fab")
		)
		(pad "1" smd custom
			(at 0 -0.4445 90)
			(size 0.1397 0.1397)
			(layers "B.Cu" "B.Mask" "B.Paste")
			(net "P3V3_STBY_R9")
			(options
				(clearance outline)
				(anchor circle)
			)
			(primitives
				(gr_poly
					(pts
						(arc
							(start -0.1778 0.2794)
							(mid -0.249642 0.249642)
							(end -0.2794 0.1778)
						)
						(arc
							(start -0.2794 -0.1778)
							(mid -0.249642 -0.249642)
							(end -0.1778 -0.2794)
						)
						(arc
							(start 0.1778 -0.2794)
							(mid 0.249642 -0.249642)
							(end 0.2794 -0.1778)
						)
						(arc
							(start 0.2794 0.1778)
							(mid 0.249642 0.249642)
							(end 0.1778 0.2794)
						)
					)
					(width 0)
					(fill yes)
				)
			)
		)
		(pad "2" smd custom
			(at 0 0.4445 90)
			(size 0.1397 0.1397)
			(layers "B.Cu" "B.Mask" "B.Paste")
			(net "P3V3_STBY_G9")
			(options
				(clearance outline)
				(anchor circle)
			)
			(primitives
				(gr_poly
					(pts
						(arc
							(start -0.1778 0.2794)
							(mid -0.249642 0.249642)
							(end -0.2794 0.1778)
						)
						(arc
							(start -0.2794 -0.1778)
							(mid -0.249642 -0.249642)
							(end -0.1778 -0.2794)
						)
						(arc
							(start 0.1778 -0.2794)
							(mid 0.249642 -0.249642)
							(end 0.2794 -0.1778)
						)
						(arc
							(start 0.2794 0.1778)
							(mid 0.249642 0.249642)
							(end 0.1778 0.2794)
						)
					)
					(width 0)
					(fill yes)
				)
			)
		)
	)
)
